# SCM (Grand Teton) — schematic netlist excerpt (pin names and nets, part order shuffled) for the footprints in the layout excerpt that follows; sources: Cadence DE-HDL packaged netlist, KiCad conversion of 12092022_DA0F0TMDCD0_F0T_Management_Board_D_brd_V3_OCP.brd

J40  SCONN16_ACASPI006P06  SCONN16_ACA-SPI-006-P06 IO  pkg SOCKET16SXA  page 45
  HOLD_N  = SPI_PCH_IO3_FLASH_R1
  VCC  = P3V3_AUX
  NC0  = RST_SPI_PCH_FLASH_R1_N
  NC1  = TP_J40_4
  NC2  = TP_J40_5
  NC3  = TP_J40_6
  CS_N  = SPI_PCH_CS0_FLASH_R1_N
  DO  = SPI_PCH_IO1_FLASH_R1
  WP_N  = SPI_PCH_IO2_FLASH_R1
  GND  = GND
  NC4  = TP_J40_11
  NC6  = TP_J40_12
  NC7  = TP_J40_13
  NC8  = TP_J40_14
  DI  = SPI_PCH_IO0_FLASH_R1
  CLK  = SPI_PCH_CLK_FLASH_R1

(kicad_pcb
	(version 20260206)
	(generator "pcbnew")
	(generator_version "10.0")
	(general
		(thickness 1.6)
		(legacy_teardrops no)
	)
	(paper "A4")
	(title_block
		(title "12092022_DA0F0TMDCD0_F0T_Management_Board_D_brd_V3_OCP.brd")
		(comment 1 "Grand Teton / footprints 441-441 of 1440")
	)
	(layers
		(0 "F.Cu" signal "TOP")
		(4 "In1.Cu" signal "GND")
		(6 "In2.Cu" signal "IN1")
		(8 "In3.Cu" signal "GND1")
		(10 "In4.Cu" signal "IN2")
		(12 "In5.Cu" signal "VCC")
		(14 "In6.Cu" signal "VCC1")
		(16 "In7.Cu" signal "IN3")
		(18 "In8.Cu" signal "GND2")
		(20 "In9.Cu" signal "IN4")
		(22 "In10.Cu" signal "GND3")
		(2 "B.Cu" signal "BOTTOM")
		(9 "F.Adhes" user "F.Adhesive")
		(11 "B.Adhes" user "B.Adhesive")
		(13 "F.Paste" user "Package Geometry/Pastemask Top")
		(15 "B.Paste" user "Package Geometry/Pastemask Bottom")
		(5 "F.SilkS" user "Ref Des/Silkscreen Top")
		(7 "B.SilkS" user "Ref Des/Silkscreen Bottom")
		(1 "F.Mask" user "Board Geometry/Soldermask Top")
		(3 "B.Mask" user "Board Geometry/Soldermask Bottom")
		(17 "Dwgs.User" user "User.Drawings")
		(19 "Cmts.User" user "User.Comments")
		(21 "Eco1.User" user "User.Eco1")
		(23 "Eco2.User" user "User.Eco2")
		(25 "Edge.Cuts" user "Board Geometry/Outline")
		(27 "Margin" user)
		(31 "F.CrtYd" user "Package Geometry/Place Bound Top")
		(29 "B.CrtYd" user "Package Geometry/Place Bound Bottom")
		(35 "F.Fab" user "Ref Des/Assembly Top")
		(33 "B.Fab" user "Ref Des/Assembly Bottom")
	)
	(footprint ""
		(layer "F.Cu")
		(at 39.500048 -97.909888 90)
		(property "Reference" "J40"
			(at 4.896358 10.069068 90)
			(unlocked yes)
			(layer "F.SilkS")
			(effects
				(font
					(size 0.7874 0.5842)
					(thickness 0.1524)
				)
				(justify left)
			)
		)
		(property "Value" ""
			(at 0 0 90)
			(layer "F.Fab")
			(effects
				(font
					(size 1.27 1.27)
				)
			)
		)
		(duplicate_pad_numbers_are_jumpers no)
		(fp_line
			(start 6.945122 -7.649972)
			(end 0 -7.649972)
			(stroke
				(width 0.1524)
				(type default)
			)
			(layer "F.SilkS")
		)
		(fp_line
			(start 6.945122 -7.649972)
			(end 6.945122 7.649972)
			(stroke
				(width 0.1524)
				(type default)
			)
			(layer "F.SilkS")
		)
		(fp_line
			(start 0 -7.649972)
			(end 8.320278 -7.649972)
			(stroke
				(width 0.1524)
				(type default)
			)
			(layer "F.SilkS")
		)
		(fp_line
			(start -6.945122 -7.649972)
			(end 0 -7.649972)
			(stroke
				(width 0.1524)
				(type default)
			)
			(layer "F.SilkS")
		)
		(fp_line
			(start -6.945122 -7.649972)
			(end -6.945122 7.649972)
			(stroke
				(width 0.1524)
				(type default)
			)
			(layer "F.SilkS")
		)
		(fp_line
			(start -10.508742 -7.649972)
			(end 0 -7.649972)
			(stroke
				(width 0.1524)
				(type default)
			)
			(layer "F.SilkS")
		)
		(fp_line
			(start -11.554968 -7.649972)
			(end -11.296142 -7.649972)
			(stroke
				(width 0.1524)
				(type default)
			)
			(layer "F.SilkS")
		)
		(fp_line
			(start -11.554968 -1.171702)
			(end -11.554968 -7.649972)
			(stroke
				(width 0.1524)
				(type default)
			)
			(layer "F.SilkS")
		)
		(fp_line
			(start -11.554968 1.368298)
			(end -11.554968 0.047498)
			(stroke
				(width 0.1524)
				(type default)
			)
			(layer "F.SilkS")
		)
		(fp_line
			(start 11.554968 2.104898)
			(end 11.554968 3.095498)
			(stroke
				(width 0.1524)
				(type default)
			)
			(layer "F.SilkS")
		)
		(fp_line
			(start -11.554968 2.993898)
			(end -11.554968 2.485898)
			(stroke
				(width 0.1524)
				(type default)
			)
			(layer "F.SilkS")
		)
		(fp_line
			(start 11.554968 4.136898)
			(end 11.554968 5.584698)
			(stroke
				(width 0.1524)
				(type default)
			)
			(layer "F.SilkS")
		)
		(fp_line
			(start -11.554968 4.238498)
			(end -11.554968 3.730498)
			(stroke
				(width 0.1524)
				(type default)
			)
			(layer "F.SilkS")
		)
		(fp_line
			(start 11.106658 7.649972)
			(end -9.010142 7.649972)
			(stroke
				(width 0.1524)
				(type default)
			)
			(layer "F.SilkS")
		)
		(fp_line
			(start 6.945122 7.649972)
			(end -6.945122 7.649972)
			(stroke
				(width 0.1524)
				(type default)
			)
			(layer "F.SilkS")
		)
		(fp_line
			(start -11.554968 7.649972)
			(end -11.554968 5.381498)
			(stroke
				(width 0.1524)
				(type default)
			)
			(layer "F.SilkS")
		)
		(fp_poly
			(pts
				(xy -7.112 -4.445) (xy -8.128 -4.953) (xy -8.128 -3.937)
			)
			(stroke
				(width 0)
				(type default)
			)
			(fill yes)
			(layer "F.SilkS")
		)
		(fp_line
			(start 6.945122 -7.649972)
			(end 6.945122 7.649972)
			(stroke
				(width 0.1)
				(type default)
			)
			(layer "F.Fab")
		)
		(fp_line
			(start -6.945122 -7.649972)
			(end 6.945122 -7.649972)
			(stroke
				(width 0.1)
				(type default)
			)
			(layer "F.Fab")
		)
		(fp_line
			(start 6.945122 7.649972)
			(end -6.945122 7.649972)
			(stroke
				(width 0.1)
				(type default)
			)
			(layer "F.Fab")
		)
		(fp_line
			(start -6.945122 7.649972)
			(end -6.945122 -7.649972)
			(stroke
				(width 0.1)
				(type default)
			)
			(layer "F.Fab")
		)
		(fp_poly
			(pts
				(xy -7.112 -4.445) (xy -8.128 -4.953) (xy -8.128 -3.937)
			)
			(stroke
				(width 0)
				(type default)
			)
			(fill yes)
			(layer "F.Fab")
		)
		(fp_text user "16"
			(at 7.49173 -5.2324 0)
			(unlocked yes)
			(layer "F.SilkS")
			(effects
				(font
					(size 0.7874 0.5842)
					(thickness 0.1524)
				)
				(justify left)
			)
		)
		(fp_text user "9"
			(at 7.51713 4.1656 0)
			(unlocked yes)
			(layer "F.SilkS")
			(effects
				(font
					(size 0.7874 0.5842)
					(thickness 0.1524)
				)
				(justify left)
			)
		)
		(fp_text user "8"
			(at -7.77367 4.2164 0)
			(unlocked yes)
			(layer "F.SilkS")
			(effects
				(font
					(size 0.7874 0.5842)
					(thickness 0.1524)
				)
				(justify left)
			)
		)
		(fp_text user "16"
			(at 7.49173 -5.2324 0)
			(unlocked yes)
			(layer "F.Fab")
			(effects
				(font
					(size 0.7874 0.5842)
					(thickness 0.1524)
				)
				(justify left)
			)
		)
		(fp_text user "9"
			(at 7.51713 4.1656 0)
			(unlocked yes)
			(layer "F.Fab")
			(effects
				(font
					(size 0.7874 0.5842)
					(thickness 0.1524)
				)
				(justify left)
			)
		)
		(fp_text user "8"
			(at -7.77367 4.2164 0)
			(unlocked yes)
			(layer "F.Fab")
			(effects
				(font
					(size 0.7874 0.5842)
					(thickness 0.1524)
				)
				(justify left)
			)
		)
		(pad "1" smd rect
			(at -4.800092 -4.445)
			(size 0.508 1.4986)
			(layers "F.Cu" "F.Mask" "F.Paste")
			(net "SPI_PCH_IO3_FLASH_R1")
		)
		(pad "2" smd rect
			(at -4.800092 -3.175)
			(size 0.508 1.4986)
			(layers "F.Cu" "F.Mask" "F.Paste")
			(net "P3V3_AUX")
		)
		(pad "3" smd rect
			(at -4.800092 -1.905)
			(size 0.508 1.4986)
			(layers "F.Cu" "F.Mask" "F.Paste")
			(net "RST_SPI_PCH_FLASH_R1_N")
		)
		(pad "4" smd rect
			(at -4.800092 -0.635)
			(size 0.508 1.4986)
			(layers "F.Cu" "F.Mask" "F.Paste")
			(net "TP_J40_4")
		)
		(pad "5" smd rect
			(at -4.800092 0.635)
			(size 0.508 1.4986)
			(layers "F.Cu" "F.Mask" "F.Paste")
			(net "TP_J40_5")
		)
		(pad "6" smd rect
			(at -4.800092 1.905)
			(size 0.508 1.4986)
			(layers "F.Cu" "F.Mask" "F.Paste")
			(net "TP_J40_6")
		)
		(pad "7" smd rect
			(at -4.800092 3.175)
			(size 0.508 1.4986)
			(layers "F.Cu" "F.Mask" "F.Paste")
			(net "SPI_PCH_CS0_FLASH_R1_N")
		)
		(pad "8" smd rect
			(at -4.800092 4.445)
			(size 0.508 1.4986)
			(layers "F.Cu" "F.Mask" "F.Paste")
			(net "SPI_PCH_IO1_FLASH_R1")
		)
		(pad "9" smd rect
			(at 4.800092 4.445)
			(size 0.508 1.4986)
			(layers "F.Cu" "F.Mask" "F.Paste")
			(net "SPI_PCH_IO2_FLASH_R1")
		)
		(pad "10" smd rect
			(at 4.800092 3.175)
			(size 0.508 1.4986)
			(layers "F.Cu" "F.Mask" "F.Paste")
			(net "GND")
		)
		(pad "11" smd rect
			(at 4.800092 1.905)
			(size 0.508 1.4986)
			(layers "F.Cu" "F.Mask" "F.Paste")
			(net "TP_J40_11")
		)
		(pad "12" smd rect
			(at 4.800092 0.635)
			(size 0.508 1.4986)
			(layers "F.Cu" "F.Mask" "F.Paste")
			(net "TP_J40_12")
		)
		(pad "13" smd rect
			(at 4.800092 -0.635)
			(size 0.508 1.4986)
			(layers "F.Cu" "F.Mask" "F.Paste")
			(net "TP_J40_13")
		)
		(pad "14" smd rect
			(at 4.800092 -1.905)
			(size 0.508 1.4986)
			(layers "F.Cu" "F.Mask" "F.Paste")
			(net "TP_J40_14")
		)
		(pad "15" smd rect
			(at 4.800092 -3.175)
			(size 0.508 1.4986)
			(layers "F.Cu" "F.Mask" "F.Paste")
			(net "SPI_PCH_IO0_FLASH_R1")
		)
		(pad "16" smd rect
			(at 4.800092 -4.445)
			(size 0.508 1.4986)
			(layers "F.Cu" "F.Mask" "F.Paste")
			(net "SPI_PCH_CLK_FLASH_R1")
		)
	)
)
